FILE_TYPE=LIBRARY_PARTS;
primitive 'SCONN75K_H17033002','SCONN75K_H17033002_SMT';
  pin
    'IO1':
      PIN_NUMBER='(1)';
      BIDIRECTIONAL='TRUE';
      INPUT_LOAD='(-0.01,0.01)';
      OUTPUT_LOAD='(1.0,-1.0)';
    'IO2':
      PIN_NUMBER='(2)';
      BIDIRECTIONAL='TRUE';
      INPUT_LOAD='(-0.01,0.01)';
      OUTPUT_LOAD='(1.0,-1.0)';
    'IO3':
      PIN_NUMBER='(3)';
      BIDIRECTIONAL='TRUE';
      INPUT_LOAD='(-0.01,0.01)';
      OUTPUT_LOAD='(1.0,-1.0)';
    'IO4':
      PIN_NUMBER='(4)';
      BIDIRECTIONAL='TRUE';
      INPUT_LOAD='(-0.01,0.01)';
      OUTPUT_LOAD='(1.0,-1.0)';
    'IO5':
      PIN_NUMBER='(5)';
      BIDIRECTIONAL='TRUE';
      INPUT_LOAD='(-0.01,0.01)';
      OUTPUT_LOAD='(1.0,-1.0)';
    'IO6':
      PIN_NUMBER='(6)';
      BIDIRECTIONAL='TRUE';
      INPUT_LOAD='(-0.01,0.01)';
      OUTPUT_LOAD='(1.0,-1.0)';
    'IO7':
      PIN_NUMBER='(7)';
      BIDIRECTIONAL='TRUE';
      INPUT_LOAD='(-0.01,0.01)';
      OUTPUT_LOAD='(1.0,-1.0)';
    'IO8':
      PIN_NUMBER='(8)';
      BIDIRECTIONAL='TRUE';
      INPUT_LOAD='(-0.01,0.01)';
      OUTPUT_LOAD='(1.0,-1.0)';
    'IO9':
      PIN_NUMBER='(9)';
      BIDIRECTIONAL='TRUE';
      INPUT_LOAD='(-0.01,0.01)';
      OUTPUT_LOAD='(1.0,-1.0)';
    'IO10':
      PIN_NUMBER='(10)';
      BIDIRECTIONAL='TRUE';
      INPUT_LOAD='(-0.01,0.01)';
      OUTPUT_LOAD='(1.0,-1.0)';
    'IO11':
      PIN_NUMBER='(11)';
      BIDIRECTIONAL='TRUE';
      INPUT_LOAD='(-0.01,0.01)';
      OUTPUT_LOAD='(1.0,-1.0)';
    'IO12':
      PIN_NUMBER='(12)';
      BIDIRECTIONAL='TRUE';
      INPUT_LOAD='(-0.01,0.01)';
      OUTPUT_LOAD='(1.0,-1.0)';
    'IO13':
      PIN_NUMBER='(13)';
      BIDIRECTIONAL='TRUE';
      INPUT_LOAD='(-0.01,0.01)';
      OUTPUT_LOAD='(1.0,-1.0)';
    'IO14':
      PIN_NUMBER='(14)';
      BIDIRECTIONAL='TRUE';
      INPUT_LOAD='(-0.01,0.01)';
      OUTPUT_LOAD='(1.0,-1.0)';
    'IO15':
      PIN_NUMBER='(15)';
      BIDIRECTIONAL='TRUE';
      INPUT_LOAD='(-0.01,0.01)';
      OUTPUT_LOAD='(1.0,-1.0)';
    'IO16':
      PIN_NUMBER='(16)';
      BIDIRECTIONAL='TRUE';
      INPUT_LOAD='(-0.01,0.01)';
      OUTPUT_LOAD='(1.0,-1.0)';
    'IO17':
      PIN_NUMBER='(17)';
      BIDIRECTIONAL='TRUE';
      INPUT_LOAD='(-0.01,0.01)';
      OUTPUT_LOAD='(1.0,-1.0)';
    'IO18':
      PIN_NUMBER='(18)';
      BIDIRECTIONAL='TRUE';
      INPUT_LOAD='(-0.01,0.01)';
      OUTPUT_LOAD='(1.0,-1.0)';
    'IO19':
      PIN_NUMBER='(19)';
      BIDIRECTIONAL='TRUE';
      INPUT_LOAD='(-0.01,0.01)';
      OUTPUT_LOAD='(1.0,-1.0)';
    'IO20':
      PIN_NUMBER='(20)';
      BIDIRECTIONAL='TRUE';
      INPUT_LOAD='(-0.01,0.01)';
      OUTPUT_LOAD='(1.0,-1.0)';
    'IO21':
      PIN_NUMBER='(21)';
      BIDIRECTIONAL='TRUE';
      INPUT_LOAD='(-0.01,0.01)';
      OUTPUT_LOAD='(1.0,-1.0)';
    'IO22':
      PIN_NUMBER='(22)';
      BIDIRECTIONAL='TRUE';
      INPUT_LOAD='(-0.01,0.01)';
      OUTPUT_LOAD='(1.0,-1.0)';
    'IO23':
      PIN_NUMBER='(23)';
      BIDIRECTIONAL='TRUE';
      INPUT_LOAD='(-0.01,0.01)';
      OUTPUT_LOAD='(1.0,-1.0)';
    'IO24':
      PIN_NUMBER='(24)';
      BIDIRECTIONAL='TRUE';
      INPUT_LOAD='(-0.01,0.01)';
      OUTPUT_LOAD='(1.0,-1.0)';
    'IO25':
      PIN_NUMBER='(25)';
      BIDIRECTIONAL='TRUE';
      INPUT_LOAD='(-0.01,0.01)';
      OUTPUT_LOAD='(1.0,-1.0)';
    'IO26':
      PIN_NUMBER='(26)';
      BIDIRECTIONAL='TRUE';
      INPUT_LOAD='(-0.01,0.01)';
      OUTPUT_LOAD='(1.0,-1.0)';
    'IO27':
      PIN_NUMBER='(27)';
      BIDIRECTIONAL='TRUE';
      INPUT_LOAD='(-0.01,0.01)';
      OUTPUT_LOAD='(1.0,-1.0)';
    'IO28':
      PIN_NUMBER='(28)';
      BIDIRECTIONAL='TRUE';
      INPUT_LOAD='(-0.01,0.01)';
      OUTPUT_LOAD='(1.0,-1.0)';
    'IO29':
      PIN_NUMBER='(29)';
      BIDIRECTIONAL='TRUE';
      INPUT_LOAD='(-0.01,0.01)';
      OUTPUT_LOAD='(1.0,-1.0)';
    'IO30':
      PIN_NUMBER='(30)';
      BIDIRECTIONAL='TRUE';
      INPUT_LOAD='(-0.01,0.01)';
      OUTPUT_LOAD='(1.0,-1.0)';
    'IO31':
      PIN_NUMBER='(31)';
      BIDIRECTIONAL='TRUE';
      INPUT_LOAD='(-0.01,0.01)';
      OUTPUT_LOAD='(1.0,-1.0)';
    'IO32':
      PIN_NUMBER='(32)';
      BIDIRECTIONAL='TRUE';
      INPUT_LOAD='(-0.01,0.01)';
      OUTPUT_LOAD='(1.0,-1.0)';
    'IO33':
      PIN_NUMBER='(33)';
      BIDIRECTIONAL='TRUE';
      INPUT_LOAD='(-0.01,0.01)';
      OUTPUT_LOAD='(1.0,-1.0)';
    'IO34':
      PIN_NUMBER='(34)';
      BIDIRECTIONAL='TRUE';
      INPUT_LOAD='(-0.01,0.01)';
      OUTPUT_LOAD='(1.0,-1.0)';
    'IO35':
      PIN_NUMBER='(35)';
      BIDIRECTIONAL='TRUE';
      INPUT_LOAD='(-0.01,0.01)';
      OUTPUT_LOAD='(1.0,-1.0)';
    'IO36':
      PIN_NUMBER='(36)';
      BIDIRECTIONAL='TRUE';
      INPUT_LOAD='(-0.01,0.01)';
      OUTPUT_LOAD='(1.0,-1.0)';
    'IO37':
      PIN_NUMBER='(37)';
      BIDIRECTIONAL='TRUE';
      INPUT_LOAD='(-0.01,0.01)';
      OUTPUT_LOAD='(1.0,-1.0)';
    'IO38':
      PIN_NUMBER='(38)';
      BIDIRECTIONAL='TRUE';
      INPUT_LOAD='(-0.01,0.01)';
      OUTPUT_LOAD='(1.0,-1.0)';
    'IO39':
      PIN_NUMBER='(39)';
      BIDIRECTIONAL='TRUE';
      INPUT_LOAD='(-0.01,0.01)';
      OUTPUT_LOAD='(1.0,-1.0)';
    'IO40':
      PIN_NUMBER='(40)';
      BIDIRECTIONAL='TRUE';
      INPUT_LOAD='(-0.01,0.01)';
      OUTPUT_LOAD='(1.0,-1.0)';
    'IO41':
      PIN_NUMBER='(41)';
      BIDIRECTIONAL='TRUE';
      INPUT_LOAD='(-0.01,0.01)';
      OUTPUT_LOAD='(1.0,-1.0)';
    'IO42':
      PIN_NUMBER='(42)';
      BIDIRECTIONAL='TRUE';
      INPUT_LOAD='(-0.01,0.01)';
      OUTPUT_LOAD='(1.0,-1.0)';
    'IO43':
      PIN_NUMBER='(43)';
      BIDIRECTIONAL='TRUE';
      INPUT_LOAD='(-0.01,0.01)';
      OUTPUT_LOAD='(1.0,-1.0)';
    'IO44':
      PIN_NUMBER='(44)';
      BIDIRECTIONAL='TRUE';
      INPUT_LOAD='(-0.01,0.01)';
      OUTPUT_LOAD='(1.0,-1.0)';
    'IO45':
      PIN_NUMBER='(45)';
      BIDIRECTIONAL='TRUE';
      INPUT_LOAD='(-0.01,0.01)';
      OUTPUT_LOAD='(1.0,-1.0)';
    'IO46':
      PIN_NUMBER='(46)';
      BIDIRECTIONAL='TRUE';
      INPUT_LOAD='(-0.01,0.01)';
      OUTPUT_LOAD='(1.0,-1.0)';
    'IO47':
      PIN_NUMBER='(47)';
      BIDIRECTIONAL='TRUE';
      INPUT_LOAD='(-0.01,0.01)';
      OUTPUT_LOAD='(1.0,-1.0)';
    'IO48':
      PIN_NUMBER='(48)';
      BIDIRECTIONAL='TRUE';
      INPUT_LOAD='(-0.01,0.01)';
      OUTPUT_LOAD='(1.0,-1.0)';
    'IO49':
      PIN_NUMBER='(49)';
      BIDIRECTIONAL='TRUE';
      INPUT_LOAD='(-0.01,0.01)';
      OUTPUT_LOAD='(1.0,-1.0)';
    'IO50':
      PIN_NUMBER='(50)';
      BIDIRECTIONAL='TRUE';
      INPUT_LOAD='(-0.01,0.01)';
      OUTPUT_LOAD='(1.0,-1.0)';
    'IO51':
      PIN_NUMBER='(51)';
      BIDIRECTIONAL='TRUE';
      INPUT_LOAD='(-0.01,0.01)';
      OUTPUT_LOAD='(1.0,-1.0)';
    'IO52':
      PIN_NUMBER='(52)';
      BIDIRECTIONAL='TRUE';
      INPUT_LOAD='(-0.01,0.01)';
      OUTPUT_LOAD='(1.0,-1.0)';
    'IO53':
      PIN_NUMBER='(53)';
      BIDIRECTIONAL='TRUE';
      INPUT_LOAD='(-0.01,0.01)';
      OUTPUT_LOAD='(1.0,-1.0)';
    'IO54':
      PIN_NUMBER='(54)';
      BIDIRECTIONAL='TRUE';
      INPUT_LOAD='(-0.01,0.01)';
      OUTPUT_LOAD='(1.0,-1.0)';
    'IO55':
      PIN_NUMBER='(55)';
      BIDIRECTIONAL='TRUE';
      INPUT_LOAD='(-0.01,0.01)';
      OUTPUT_LOAD='(1.0,-1.0)';
    'IO56':
      PIN_NUMBER='(56)';
      BIDIRECTIONAL='TRUE';
      INPUT_LOAD='(-0.01,0.01)';
      OUTPUT_LOAD='(1.0,-1.0)';
    'IO57':
      PIN_NUMBER='(57)';
      BIDIRECTIONAL='TRUE';
      INPUT_LOAD='(-0.01,0.01)';
      OUTPUT_LOAD='(1.0,-1.0)';
    'IO58':
      PIN_NUMBER='(58)';
      BIDIRECTIONAL='TRUE';
      INPUT_LOAD='(-0.01,0.01)';
      OUTPUT_LOAD='(1.0,-1.0)';
    'IO67':
      PIN_NUMBER='(67)';
      BIDIRECTIONAL='TRUE';
      INPUT_LOAD='(-0.01,0.01)';
      OUTPUT_LOAD='(1.0,-1.0)';
    'IO68':
      PIN_NUMBER='(68)';
      BIDIRECTIONAL='TRUE';
      INPUT_LOAD='(-0.01,0.01)';
      OUTPUT_LOAD='(1.0,-1.0)';
    'IO69':
      PIN_NUMBER='(69)';
      BIDIRECTIONAL='TRUE';
      INPUT_LOAD='(-0.01,0.01)';
      OUTPUT_LOAD='(1.0,-1.0)';
    'IO70':
      PIN_NUMBER='(70)';
      BIDIRECTIONAL='TRUE';
      INPUT_LOAD='(-0.01,0.01)';
      OUTPUT_LOAD='(1.0,-1.0)';
    'IO71':
      PIN_NUMBER='(71)';
      BIDIRECTIONAL='TRUE';
      INPUT_LOAD='(-0.01,0.01)';
      OUTPUT_LOAD='(1.0,-1.0)';
    'IO72':
      PIN_NUMBER='(72)';
      BIDIRECTIONAL='TRUE';
      INPUT_LOAD='(-0.01,0.01)';
      OUTPUT_LOAD='(1.0,-1.0)';
    'IO73':
      PIN_NUMBER='(73)';
      BIDIRECTIONAL='TRUE';
      INPUT_LOAD='(-0.01,0.01)';
      OUTPUT_LOAD='(1.0,-1.0)';
    'IO74':
      PIN_NUMBER='(74)';
      BIDIRECTIONAL='TRUE';
      INPUT_LOAD='(-0.01,0.01)';
      OUTPUT_LOAD='(1.0,-1.0)';
    'IO75':
      PIN_NUMBER='(75)';
      BIDIRECTIONAL='TRUE';
      INPUT_LOAD='(-0.01,0.01)';
      OUTPUT_LOAD='(1.0,-1.0)';
    'MP1':
      PIN_NUMBER='(MP1)';
      PINUSE='GROUND';
      NO_LOAD_CHECK='Both';
      NO_IO_CHECK='Both';
      NO_ASSERT_CHECK='TRUE';
      NO_DIR_CHECK='TRUE';
      ALLOW_CONNECT='TRUE';
    'MP2':
      PIN_NUMBER='(MP2)';
      PINUSE='GROUND';
      NO_LOAD_CHECK='Both';
      NO_IO_CHECK='Both';
      NO_ASSERT_CHECK='TRUE';
      NO_DIR_CHECK='TRUE';
      ALLOW_CONNECT='TRUE';
  end_pin;
  body
    PART_NAME='SCONN75K_H17033002';
    BODY_NAME='SCONN75K_H17033002';
    PHYS_DES_PREFIX='J';
  end_body;
end_primitive;

primitive 'SCONN75K_H17033002_SMT1';
  pin
    'GND'<0>:
      PIN_NUMBER='(1)';
      PINUSE='GROUND';
      NO_LOAD_CHECK='Both';
      NO_IO_CHECK='Both';
      NO_ASSERT_CHECK='TRUE';
      NO_DIR_CHECK='TRUE';
      ALLOW_CONNECT='TRUE';
    '3_3V'<0>:
      PIN_NUMBER='(2)';
      PINUSE='POWER';
      NO_LOAD_CHECK='Both';
      NO_IO_CHECK='Both';
      NO_ASSERT_CHECK='TRUE';
      NO_DIR_CHECK='TRUE';
      ALLOW_CONNECT='TRUE';
    'GND'<1>:
      PIN_NUMBER='(3)';
      PINUSE='GROUND';
      NO_LOAD_CHECK='Both';
      NO_IO_CHECK='Both';
      NO_ASSERT_CHECK='TRUE';
      NO_DIR_CHECK='TRUE';
      ALLOW_CONNECT='TRUE';
    '3_3V'<1>:
      PIN_NUMBER='(4)';
      PINUSE='POWER';
      NO_LOAD_CHECK='Both';
      NO_IO_CHECK='Both';
      NO_ASSERT_CHECK='TRUE';
      NO_DIR_CHECK='TRUE';
      ALLOW_CONNECT='TRUE';
    'PERN3':
      PIN_NUMBER='(5)';
      BIDIRECTIONAL='TRUE';
      INPUT_LOAD='(-0.01,0.01)';
      OUTPUT_LOAD='(1.0,-1.0)';
    'NC'<0>:
      PIN_NUMBER='(6)';
      PINUSE='NC';
      NO_LOAD_CHECK='Both';
      NO_IO_CHECK='Both';
      NO_ASSERT_CHECK='TRUE';
      NO_DIR_CHECK='TRUE';
      ALLOW_CONNECT='TRUE';
    'PERP3':
      PIN_NUMBER='(7)';
      BIDIRECTIONAL='TRUE';
      INPUT_LOAD='(-0.01,0.01)';
      OUTPUT_LOAD='(1.0,-1.0)';
    'NC'<1>:
      PIN_NUMBER='(8)';
      PINUSE='NC';
      NO_LOAD_CHECK='Both';
      NO_IO_CHECK='Both';
      NO_ASSERT_CHECK='TRUE';
      NO_DIR_CHECK='TRUE';
      ALLOW_CONNECT='TRUE';
    'GND'<2>:
      PIN_NUMBER='(9)';
      PINUSE='GROUND';
      NO_LOAD_CHECK='Both';
      NO_IO_CHECK='Both';
      NO_ASSERT_CHECK='TRUE';
      NO_DIR_CHECK='TRUE';
      ALLOW_CONNECT='TRUE';
    'DAS_DSS_N':
      PIN_NUMBER='(10)';
      INPUT_LOAD='(-0.01,0.01)';
    'PETN3':
      PIN_NUMBER='(11)';
      BIDIRECTIONAL='TRUE';
      INPUT_LOAD='(-0.01,0.01)';
      OUTPUT_LOAD='(1.0,-1.0)';
    '3_3V'<2>:
      PIN_NUMBER='(12)';
      PINUSE='POWER';
      NO_LOAD_CHECK='Both';
      NO_IO_CHECK='Both';
      NO_ASSERT_CHECK='TRUE';
      NO_DIR_CHECK='TRUE';
      ALLOW_CONNECT='TRUE';
    'PETP3':
      PIN_NUMBER='(13)';
      BIDIRECTIONAL='TRUE';
      INPUT_LOAD='(-0.01,0.01)';
      OUTPUT_LOAD='(1.0,-1.0)';
    '3_3V'<3>:
      PIN_NUMBER='(14)';
      PINUSE='POWER';
      NO_LOAD_CHECK='Both';
      NO_IO_CHECK='Both';
      NO_ASSERT_CHECK='TRUE';
      NO_DIR_CHECK='TRUE';
      ALLOW_CONNECT='TRUE';
    'GND'<3>:
      PIN_NUMBER='(15)';
      PINUSE='GROUND';
      NO_LOAD_CHECK='Both';
      NO_IO_CHECK='Both';
      NO_ASSERT_CHECK='TRUE';
      NO_DIR_CHECK='TRUE';
      ALLOW_CONNECT='TRUE';
    '3_3V'<4>:
      PIN_NUMBER='(16)';
      PINUSE='POWER';
      NO_LOAD_CHECK='Both';
      NO_IO_CHECK='Both';
      NO_ASSERT_CHECK='TRUE';
      NO_DIR_CHECK='TRUE';
      ALLOW_CONNECT='TRUE';
    'PERN2':
      PIN_NUMBER='(17)';
      BIDIRECTIONAL='TRUE';
      INPUT_LOAD='(-0.01,0.01)';
      OUTPUT_LOAD='(1.0,-1.0)';
    '3_3V'<5>:
      PIN_NUMBER='(18)';
      PINUSE='POWER';
      NO_LOAD_CHECK='Both';
      NO_IO_CHECK='Both';
      NO_ASSERT_CHECK='TRUE';
      NO_DIR_CHECK='TRUE';
      ALLOW_CONNECT='TRUE';
    'PERP2':
      PIN_NUMBER='(19)';
      BIDIRECTIONAL='TRUE';
      INPUT_LOAD='(-0.01,0.01)';
      OUTPUT_LOAD='(1.0,-1.0)';
    'NC'<2>:
      PIN_NUMBER='(20)';
      PINUSE='NC';
      NO_LOAD_CHECK='Both';
      NO_IO_CHECK='Both';
      NO_ASSERT_CHECK='TRUE';
      NO_DIR_CHECK='TRUE';
      ALLOW_CONNECT='TRUE';
    'GND'<4>:
      PIN_NUMBER='(21)';
      PINUSE='GROUND';
      NO_LOAD_CHECK='Both';
      NO_IO_CHECK='Both';
      NO_ASSERT_CHECK='TRUE';
      NO_DIR_CHECK='TRUE';
      ALLOW_CONNECT='TRUE';
    'NC'<3>:
      PIN_NUMBER='(22)';
      PINUSE='NC';
      NO_LOAD_CHECK='Both';
      NO_IO_CHECK='Both';
      NO_ASSERT_CHECK='TRUE';
      NO_DIR_CHECK='TRUE';
      ALLOW_CONNECT='TRUE';
    'PETN2':
      PIN_NUMBER='(23)';
      BIDIRECTIONAL='TRUE';
      INPUT_LOAD='(-0.01,0.01)';
      OUTPUT_LOAD='(1.0,-1.0)';
    'NC'<4>:
      PIN_NUMBER='(24)';
      PINUSE='NC';
      NO_LOAD_CHECK='Both';
      NO_IO_CHECK='Both';
      NO_ASSERT_CHECK='TRUE';
      NO_DIR_CHECK='TRUE';
      ALLOW_CONNECT='TRUE';
    'PETP2':
      PIN_NUMBER='(25)';
      BIDIRECTIONAL='TRUE';
      INPUT_LOAD='(-0.01,0.01)';
      OUTPUT_LOAD='(1.0,-1.0)';
    'NC'<5>:
      PIN_NUMBER='(26)';
      PINUSE='NC';
      NO_LOAD_CHECK='Both';
      NO_IO_CHECK='Both';
      NO_ASSERT_CHECK='TRUE';
      NO_DIR_CHECK='TRUE';
      ALLOW_CONNECT='TRUE';
    'GND'<5>:
      PIN_NUMBER='(27)';
      PINUSE='GROUND';
      NO_LOAD_CHECK='Both';
      NO_IO_CHECK='Both';
      NO_ASSERT_CHECK='TRUE';
      NO_DIR_CHECK='TRUE';
      ALLOW_CONNECT='TRUE';
    'NC'<6>:
      PIN_NUMBER='(28)';
      PINUSE='NC';
      NO_LOAD_CHECK='Both';
      NO_IO_CHECK='Both';
      NO_ASSERT_CHECK='TRUE';
      NO_DIR_CHECK='TRUE';
      ALLOW_CONNECT='TRUE';
    'PERN1':
      PIN_NUMBER='(29)';
      BIDIRECTIONAL='TRUE';
      INPUT_LOAD='(-0.01,0.01)';
      OUTPUT_LOAD='(1.0,-1.0)';
    'NC'<7>:
      PIN_NUMBER='(30)';
      PINUSE='NC';
      NO_LOAD_CHECK='Both';
      NO_IO_CHECK='Both';
      NO_ASSERT_CHECK='TRUE';
      NO_DIR_CHECK='TRUE';
      ALLOW_CONNECT='TRUE';
    'PERP1':
      PIN_NUMBER='(31)';
      BIDIRECTIONAL='TRUE';
      INPUT_LOAD='(-0.01,0.01)';
      OUTPUT_LOAD='(1.0,-1.0)';
    'NC'<8>:
      PIN_NUMBER='(32)';
      PINUSE='NC';
      NO_LOAD_CHECK='Both';
      NO_IO_CHECK='Both';
      NO_ASSERT_CHECK='TRUE';
      NO_DIR_CHECK='TRUE';
      ALLOW_CONNECT='TRUE';
    'GND'<6>:
      PIN_NUMBER='(33)';
      PINUSE='GROUND';
      NO_LOAD_CHECK='Both';
      NO_IO_CHECK='Both';
      NO_ASSERT_CHECK='TRUE';
      NO_DIR_CHECK='TRUE';
      ALLOW_CONNECT='TRUE';
    'NC'<9>:
      PIN_NUMBER='(34)';
      PINUSE='NC';
      NO_LOAD_CHECK='Both';
      NO_IO_CHECK='Both';
      NO_ASSERT_CHECK='TRUE';
      NO_DIR_CHECK='TRUE';
      ALLOW_CONNECT='TRUE';
    'PETN1':
      PIN_NUMBER='(35)';
      BIDIRECTIONAL='TRUE';
      INPUT_LOAD='(-0.01,0.01)';
      OUTPUT_LOAD='(1.0,-1.0)';
    'NC'<10>:
      PIN_NUMBER='(36)';
      PINUSE='NC';
      NO_LOAD_CHECK='Both';
      NO_IO_CHECK='Both';
      NO_ASSERT_CHECK='TRUE';
      NO_DIR_CHECK='TRUE';
      ALLOW_CONNECT='TRUE';
    'PETP1':
      PIN_NUMBER='(37)';
      BIDIRECTIONAL='TRUE';
      INPUT_LOAD='(-0.01,0.01)';
      OUTPUT_LOAD='(1.0,-1.0)';
    'DEVSLP':
      PIN_NUMBER='(38)';
      OUTPUT_LOAD='(1.0,-1.0)';
    'GND'<7>:
      PIN_NUMBER='(39)';
      PINUSE='GROUND';
      NO_LOAD_CHECK='Both';
      NO_IO_CHECK='Both';
      NO_ASSERT_CHECK='TRUE';
      NO_DIR_CHECK='TRUE';
      ALLOW_CONNECT='TRUE';
    'NC'<11>:
      PIN_NUMBER='(40)';
      PINUSE='NC';
      NO_LOAD_CHECK='Both';
      NO_IO_CHECK='Both';
      NO_ASSERT_CHECK='TRUE';
      NO_DIR_CHECK='TRUE';
      ALLOW_CONNECT='TRUE';
    'PERN0_SATA_BP':
      PIN_NUMBER='(41)';
      BIDIRECTIONAL='TRUE';
      INPUT_LOAD='(-0.01,0.01)';
      OUTPUT_LOAD='(1.0,-1.0)';
    'NC'<12>:
      PIN_NUMBER='(42)';
      PINUSE='NC';
      NO_LOAD_CHECK='Both';
      NO_IO_CHECK='Both';
      NO_ASSERT_CHECK='TRUE';
      NO_DIR_CHECK='TRUE';
      ALLOW_CONNECT='TRUE';
    'PERP0_SATA_BN':
      PIN_NUMBER='(43)';
      BIDIRECTIONAL='TRUE';
      INPUT_LOAD='(-0.01,0.01)';
      OUTPUT_LOAD='(1.0,-1.0)';
    'NC'<13>:
      PIN_NUMBER='(44)';
      PINUSE='NC';
      NO_LOAD_CHECK='Both';
      NO_IO_CHECK='Both';
      NO_ASSERT_CHECK='TRUE';
      NO_DIR_CHECK='TRUE';
      ALLOW_CONNECT='TRUE';
    'GND'<8>:
      PIN_NUMBER='(45)';
      PINUSE='GROUND';
      NO_LOAD_CHECK='Both';
      NO_IO_CHECK='Both';
      NO_ASSERT_CHECK='TRUE';
      NO_DIR_CHECK='TRUE';
      ALLOW_CONNECT='TRUE';
    'NC'<14>:
      PIN_NUMBER='(46)';
      PINUSE='NC';
      NO_LOAD_CHECK='Both';
      NO_IO_CHECK='Both';
      NO_ASSERT_CHECK='TRUE';
      NO_DIR_CHECK='TRUE';
      ALLOW_CONNECT='TRUE';
    'PETN0_SATA_AN':
      PIN_NUMBER='(47)';
      BIDIRECTIONAL='TRUE';
      INPUT_LOAD='(-0.01,0.01)';
      OUTPUT_LOAD='(1.0,-1.0)';
    'NC'<15>:
      PIN_NUMBER='(48)';
      PINUSE='NC';
      NO_LOAD_CHECK='Both';
      NO_IO_CHECK='Both';
      NO_ASSERT_CHECK='TRUE';
      NO_DIR_CHECK='TRUE';
      ALLOW_CONNECT='TRUE';
    'PETP0_SATA_AP':
      PIN_NUMBER='(49)';
      BIDIRECTIONAL='TRUE';
      INPUT_LOAD='(-0.01,0.01)';
      OUTPUT_LOAD='(1.0,-1.0)';
    'PERST_N_NC':
      PIN_NUMBER='(50)';
      OUTPUT_LOAD='(1.0,-1.0)';
    'GND'<9>:
      PIN_NUMBER='(51)';
      PINUSE='GROUND';
      NO_LOAD_CHECK='Both';
      NO_IO_CHECK='Both';
      NO_ASSERT_CHECK='TRUE';
      NO_DIR_CHECK='TRUE';
      ALLOW_CONNECT='TRUE';
    'CLKREQ_N_NC':
      PIN_NUMBER='(52)';
      BIDIRECTIONAL='TRUE';
      INPUT_LOAD='(-0.01,0.01)';
      OUTPUT_LOAD='(1.0,-1.0)';
    'REFCLKN':
      PIN_NUMBER='(53)';
      BIDIRECTIONAL='TRUE';
      INPUT_LOAD='(-0.01,0.01)';
      OUTPUT_LOAD='(1.0,-1.0)';
    'PEWAKE_N_NC':
      PIN_NUMBER='(54)';
      BIDIRECTIONAL='TRUE';
      INPUT_LOAD='(-0.01,0.01)';
      OUTPUT_LOAD='(1.0,-1.0)';
    'REFCLKP':
      PIN_NUMBER='(55)';
      BIDIRECTIONAL='TRUE';
      INPUT_LOAD='(-0.01,0.01)';
      OUTPUT_LOAD='(1.0,-1.0)';
    'NC'<16>:
      PIN_NUMBER='(56)';
      PINUSE='NC';
      NO_LOAD_CHECK='Both';
      NO_IO_CHECK='Both';
      NO_ASSERT_CHECK='TRUE';
      NO_DIR_CHECK='TRUE';
      ALLOW_CONNECT='TRUE';
    'GND'<10>:
      PIN_NUMBER='(57)';
      PINUSE='GROUND';
      NO_LOAD_CHECK='Both';
      NO_IO_CHECK='Both';
      NO_ASSERT_CHECK='TRUE';
      NO_DIR_CHECK='TRUE';
      ALLOW_CONNECT='TRUE';
    'NC'<17>:
      PIN_NUMBER='(58)';
      PINUSE='NC';
      NO_LOAD_CHECK='Both';
      NO_IO_CHECK='Both';
      NO_ASSERT_CHECK='TRUE';
      NO_DIR_CHECK='TRUE';
      ALLOW_CONNECT='TRUE';
    'NC'<18>:
      PIN_NUMBER='(67)';
      PINUSE='NC';
      NO_LOAD_CHECK='Both';
      NO_IO_CHECK='Both';
      NO_ASSERT_CHECK='TRUE';
      NO_DIR_CHECK='TRUE';
      ALLOW_CONNECT='TRUE';
    'SUSCLK':
      PIN_NUMBER='(68)';
      OUTPUT_LOAD='(1.0,-1.0)';
    'PEDET':
      PIN_NUMBER='(69)';
      BIDIRECTIONAL='TRUE';
      INPUT_LOAD='(-0.01,0.01)';
      OUTPUT_LOAD='(1.0,-1.0)';
    '3_3V'<6>:
      PIN_NUMBER='(70)';
      PINUSE='POWER';
      NO_LOAD_CHECK='Both';
      NO_IO_CHECK='Both';
      NO_ASSERT_CHECK='TRUE';
      NO_DIR_CHECK='TRUE';
      ALLOW_CONNECT='TRUE';
    'GND'<11>:
      PIN_NUMBER='(71)';
      PINUSE='GROUND';
      NO_LOAD_CHECK='Both';
      NO_IO_CHECK='Both';
      NO_ASSERT_CHECK='TRUE';
      NO_DIR_CHECK='TRUE';
      ALLOW_CONNECT='TRUE';
    '3_3V'<7>:
      PIN_NUMBER='(72)';
      PINUSE='POWER';
      NO_LOAD_CHECK='Both';
      NO_IO_CHECK='Both';
      NO_ASSERT_CHECK='TRUE';
      NO_DIR_CHECK='TRUE';
      ALLOW_CONNECT='TRUE';
    'GND'<12>:
      PIN_NUMBER='(73)';
      PINUSE='GROUND';
      NO_LOAD_CHECK='Both';
      NO_IO_CHECK='Both';
      NO_ASSERT_CHECK='TRUE';
      NO_DIR_CHECK='TRUE';
      ALLOW_CONNECT='TRUE';
    '3_3V'<8>:
      PIN_NUMBER='(74)';
      PINUSE='POWER';
      NO_LOAD_CHECK='Both';
      NO_IO_CHECK='Both';
      NO_ASSERT_CHECK='TRUE';
      NO_DIR_CHECK='TRUE';
      ALLOW_CONNECT='TRUE';
    'GND'<13>:
      PIN_NUMBER='(75)';
      PINUSE='GROUND';
      NO_LOAD_CHECK='Both';
      NO_IO_CHECK='Both';
      NO_ASSERT_CHECK='TRUE';
      NO_DIR_CHECK='TRUE';
      ALLOW_CONNECT='TRUE';
    'MP1':
      PIN_NUMBER='(MP1)';
      PINUSE='GROUND';
      NO_LOAD_CHECK='Both';
      NO_IO_CHECK='Both';
      NO_ASSERT_CHECK='TRUE';
      NO_DIR_CHECK='TRUE';
      ALLOW_CONNECT='TRUE';
    'MP2':
      PIN_NUMBER='(MP2)';
      PINUSE='GROUND';
      NO_LOAD_CHECK='Both';
      NO_IO_CHECK='Both';
      NO_ASSERT_CHECK='TRUE';
      NO_DIR_CHECK='TRUE';
      ALLOW_CONNECT='TRUE';
  end_pin;
  body
    PART_NAME='SCONN75K_H17033002';
    BODY_NAME='SCONN75K_H17033002';
    PHYS_DES_PREFIX='J';
  end_body;
end_primitive;

END.
